(kicad_pcb
	(version 20260206)
	(generator "pcbnew")
	(generator_version "10.0")
	(general
		(thickness 1.6)
		(legacy_teardrops no)
	)
	(paper "A4")
	(title_block
		(title "01162023_DA0F0TEBIF0_F0T_Expander_BD_F_brd_V02_OCP.brd")
		(comment 1 "Grand Teton / footprints 6992-6997 of 9728")
	)
	(layers
		(0 "F.Cu" signal "TOP")
		(4 "In1.Cu" signal "GND")
		(6 "In2.Cu" signal "VCC")
		(8 "In3.Cu" signal "VCC1")
		(10 "In4.Cu" signal "GND1")
		(12 "In5.Cu" signal "IN1")
		(14 "In6.Cu" signal "GND2")
		(16 "In7.Cu" signal "IN2")
		(18 "In8.Cu" signal "GND3")
		(20 "In9.Cu" signal "IN3")
		(22 "In10.Cu" signal "GND4")
		(24 "In11.Cu" signal "IN4")
		(26 "In12.Cu" signal "GND5")
		(28 "In13.Cu" signal "IN5")
		(30 "In14.Cu" signal "GND6")
		(32 "In15.Cu" signal "IN6")
		(34 "In16.Cu" signal "GND7")
		(2 "B.Cu" signal "BOTTOM")
		(9 "F.Adhes" user "F.Adhesive")
		(11 "B.Adhes" user "B.Adhesive")
		(13 "F.Paste" user "Package Geometry/Pastemask Top")
		(15 "B.Paste" user "Package Geometry/Pastemask Bottom")
		(5 "F.SilkS" user "Ref Des/Silkscreen Top")
		(7 "B.SilkS" user "Ref Des/Silkscreen Bottom")
		(1 "F.Mask" user "Board Geometry/Soldermask Top")
		(3 "B.Mask" user "Board Geometry/Soldermask Bottom")
		(17 "Dwgs.User" user "User.Drawings")
		(19 "Cmts.User" user "User.Comments")
		(21 "Eco1.User" user "User.Eco1")
		(23 "Eco2.User" user "User.Eco2")
		(25 "Edge.Cuts" user "Board Geometry/Outline")
		(27 "Margin" user)
		(31 "F.CrtYd" user "Package Geometry/Place Bound Top")
		(29 "B.CrtYd" user "Package Geometry/Place Bound Bottom")
		(35 "F.Fab" user "Ref Des/Assembly Top")
		(33 "B.Fab" user "Ref Des/Assembly Bottom")
	)
	(footprint ""
		(layer "F.Cu")
		(at 219.202 -194.056)
		(property "Reference" "R1529"
			(at 0 0 0)
			(layer "F.SilkS")
			(hide yes)
			(effects
				(font
					(size 1.27 1.27)
				)
			)
		)
		(property "Value" ""
			(at 0 0 0)
			(layer "F.Fab")
			(effects
				(font
					(size 1.27 1.27)
				)
			)
		)
		(duplicate_pad_numbers_are_jumpers no)
		(fp_line
			(start -0.7874 -0.4064)
			(end 0.7874 -0.4064)
			(stroke
				(width 0.1524)
				(type default)
			)
			(layer "F.SilkS")
		)
		(fp_line
			(start -0.7874 0.4064)
			(end -0.7874 -0.4064)
			(stroke
				(width 0.1524)
				(type default)
			)
			(layer "F.SilkS")
		)
		(fp_line
			(start 0.7874 -0.4064)
			(end 0.7874 0.4064)
			(stroke
				(width 0.1524)
				(type default)
			)
			(layer "F.SilkS")
		)
		(fp_line
			(start 0.7874 0.4064)
			(end -0.7874 0.4064)
			(stroke
				(width 0.1524)
				(type default)
			)
			(layer "F.SilkS")
		)
		(fp_line
			(start -0.67945 -0.305054)
			(end -0.12065 -0.305054)
			(stroke
				(width 0.1)
				(type default)
			)
			(layer "F.Fab")
		)
		(fp_line
			(start -0.67945 0.3048)
			(end -0.67945 -0.305054)
			(stroke
				(width 0.1)
				(type default)
			)
			(layer "F.Fab")
		)
		(fp_line
			(start -0.12065 -0.305054)
			(end -0.12065 -0.2794)
			(stroke
				(width 0.1)
				(type default)
			)
			(layer "F.Fab")
		)
		(fp_line
			(start -0.12065 -0.2794)
			(end 0.12065 -0.2794)
			(stroke
				(width 0.1)
				(type default)
			)
			(layer "F.Fab")
		)
		(fp_line
			(start -0.12065 0.2794)
			(end -0.12065 0.3048)
			(stroke
				(width 0.1)
				(type default)
			)
			(layer "F.Fab")
		)
		(fp_line
			(start -0.12065 0.3048)
			(end -0.67945 0.3048)
			(stroke
				(width 0.1)
				(type default)
			)
			(layer "F.Fab")
		)
		(fp_line
			(start 0.120396 0.2794)
			(end -0.12065 0.2794)
			(stroke
				(width 0.1)
				(type default)
			)
			(layer "F.Fab")
		)
		(fp_line
			(start 0.120396 0.3048)
			(end 0.120396 0.2794)
			(stroke
				(width 0.1)
				(type default)
			)
			(layer "F.Fab")
		)
		(fp_line
			(start 0.12065 -0.3048)
			(end 0.67945 -0.3048)
			(stroke
				(width 0.1)
				(type default)
			)
			(layer "F.Fab")
		)
		(fp_line
			(start 0.12065 -0.2794)
			(end 0.12065 -0.3048)
			(stroke
				(width 0.1)
				(type default)
			)
			(layer "F.Fab")
		)
		(fp_line
			(start 0.67945 -0.3048)
			(end 0.67945 0.3048)
			(stroke
				(width 0.1)
				(type default)
			)
			(layer "F.Fab")
		)
		(fp_line
			(start 0.67945 0.3048)
			(end 0.120396 0.3048)
			(stroke
				(width 0.1)
				(type default)
			)
			(layer "F.Fab")
		)
		(pad "1" smd circle
			(at -0.40005 0)
			(size 0 0)
			(layers "F.Cu" "F.Mask" "F.Paste")
			(net "SMB_NIC7_LS_R_SDA")
		)
		(pad "2" smd circle
			(at 0.40005 0)
			(size 0 0)
			(layers "F.Cu" "F.Mask" "F.Paste")
			(net "P3V3_NIC7")
		)
	)
	(footprint ""
		(layer "F.Cu")
		(at 106.7816 -202.466956 90)
		(property "Reference" "R6630"
			(at 0 0 90)
			(layer "F.SilkS")
			(hide yes)
			(effects
				(font
					(size 1.27 1.27)
				)
			)
		)
		(property "Value" ""
			(at 0 0 90)
			(layer "F.Fab")
			(effects
				(font
					(size 1.27 1.27)
				)
			)
		)
		(duplicate_pad_numbers_are_jumpers no)
		(fp_line
			(start 0.7874 -0.4064)
			(end 0.7874 0.4064)
			(stroke
				(width 0.1524)
				(type default)
			)
			(layer "F.SilkS")
		)
		(fp_line
			(start -0.7874 -0.4064)
			(end 0.7874 -0.4064)
			(stroke
				(width 0.1524)
				(type default)
			)
			(layer "F.SilkS")
		)
		(fp_line
			(start 0.7874 0.4064)
			(end -0.7874 0.4064)
			(stroke
				(width 0.1524)
				(type default)
			)
			(layer "F.SilkS")
		)
		(fp_line
			(start -0.7874 0.4064)
			(end -0.7874 -0.4064)
			(stroke
				(width 0.1524)
				(type default)
			)
			(layer "F.SilkS")
		)
		(fp_line
			(start -0.12065 -0.305054)
			(end -0.12065 -0.2794)
			(stroke
				(width 0.1)
				(type default)
			)
			(layer "F.Fab")
		)
		(fp_line
			(start -0.67945 -0.305054)
			(end -0.12065 -0.305054)
			(stroke
				(width 0.1)
				(type default)
			)
			(layer "F.Fab")
		)
		(fp_line
			(start 0.67945 -0.3048)
			(end 0.67945 0.3048)
			(stroke
				(width 0.1)
				(type default)
			)
			(layer "F.Fab")
		)
		(fp_line
			(start 0.12065 -0.3048)
			(end 0.67945 -0.3048)
			(stroke
				(width 0.1)
				(type default)
			)
			(layer "F.Fab")
		)
		(fp_line
			(start 0.12065 -0.2794)
			(end 0.12065 -0.3048)
			(stroke
				(width 0.1)
				(type default)
			)
			(layer "F.Fab")
		)
		(fp_line
			(start -0.12065 -0.2794)
			(end 0.12065 -0.2794)
			(stroke
				(width 0.1)
				(type default)
			)
			(layer "F.Fab")
		)
		(fp_line
			(start 0.120396 0.2794)
			(end -0.12065 0.2794)
			(stroke
				(width 0.1)
				(type default)
			)
			(layer "F.Fab")
		)
		(fp_line
			(start -0.12065 0.2794)
			(end -0.12065 0.3048)
			(stroke
				(width 0.1)
				(type default)
			)
			(layer "F.Fab")
		)
		(fp_line
			(start 0.67945 0.3048)
			(end 0.120396 0.3048)
			(stroke
				(width 0.1)
				(type default)
			)
			(layer "F.Fab")
		)
		(fp_line
			(start 0.120396 0.3048)
			(end 0.120396 0.2794)
			(stroke
				(width 0.1)
				(type default)
			)
			(layer "F.Fab")
		)
		(fp_line
			(start -0.12065 0.3048)
			(end -0.67945 0.3048)
			(stroke
				(width 0.1)
				(type default)
			)
			(layer "F.Fab")
		)
		(fp_line
			(start -0.67945 0.3048)
			(end -0.67945 -0.305054)
			(stroke
				(width 0.1)
				(type default)
			)
			(layer "F.Fab")
		)
		(pad "1" smd circle
			(at -0.40005 0 90)
			(size 0 0)
			(layers "F.Cu" "F.Mask" "F.Paste")
			(net "UART_PEX1_CLI_CP2108_RX")
		)
		(pad "2" smd circle
			(at 0.40005 0 90)
			(size 0 0)
			(layers "F.Cu" "F.Mask" "F.Paste")
			(net "UART_PEX1_CLI_R_RX")
		)
	)
	(footprint ""
		(layer "F.Cu")
		(at 38.875208 -350.098614 90)
		(property "Reference" "C173"
			(at 0 0 90)
			(layer "F.SilkS")
			(hide yes)
			(effects
				(font
					(size 1.27 1.27)
				)
			)
		)
		(property "Value" ""
			(at 0 0 90)
			(layer "F.Fab")
			(effects
				(font
					(size 1.27 1.27)
				)
			)
		)
		(duplicate_pad_numbers_are_jumpers no)
		(fp_line
			(start 0.299974 -0.150114)
			(end 0.299974 0.150114)
			(stroke
				(width 0.1)
				(type default)
			)
			(layer "F.Fab")
		)
		(fp_line
			(start -0.299974 -0.150114)
			(end 0.299974 -0.150114)
			(stroke
				(width 0.1)
				(type default)
			)
			(layer "F.Fab")
		)
		(fp_line
			(start 0.299974 0.150114)
			(end -0.299974 0.150114)
			(stroke
				(width 0.1)
				(type default)
			)
			(layer "F.Fab")
		)
		(fp_line
			(start -0.299974 0.150114)
			(end -0.299974 -0.150114)
			(stroke
				(width 0.1)
				(type default)
			)
			(layer "F.Fab")
		)
		(pad "1" smd rect
			(at -0.2667 0 90)
			(size 0.3048 0.381)
			(layers "F.Cu" "F.Mask" "F.Paste")
			(net "P5E_PEX0_STN7_TX_DP<121>")
		)
		(pad "2" smd rect
			(at 0.2667 0 90)
			(size 0.3048 0.381)
			(layers "F.Cu" "F.Mask" "F.Paste")
			(net "P5E_PEX0_STN7_TX_C_DP<121>")
		)
	)
	(footprint ""
		(layer "F.Cu")
		(at 207.724502 -114.311176 90)
		(property "Reference" "PU102"
			(at 1.765554 -3.457702 0)
			(unlocked yes)
			(layer "F.SilkS")
			(effects
				(font
					(size 0.7874 0.5842)
					(thickness 0.1524)
				)
			)
		)
		(property "Value" ""
			(at 0 0 90)
			(layer "F.Fab")
			(effects
				(font
					(size 1.27 1.27)
				)
			)
		)
		(duplicate_pad_numbers_are_jumpers no)
		(fp_line
			(start 1.239774 -1.495298)
			(end 1.239774 1.495298)
			(stroke
				(width 0.1524)
				(type default)
			)
			(layer "F.SilkS")
		)
		(fp_line
			(start -1.239774 -1.495298)
			(end 1.239774 -1.495298)
			(stroke
				(width 0.1524)
				(type default)
			)
			(layer "F.SilkS")
		)
		(fp_line
			(start 1.239774 1.495298)
			(end -1.239774 1.495298)
			(stroke
				(width 0.1524)
				(type default)
			)
			(layer "F.SilkS")
		)
		(fp_line
			(start -1.239774 1.495298)
			(end -1.239774 -1.495298)
			(stroke
				(width 0.1524)
				(type default)
			)
			(layer "F.SilkS")
		)
		(fp_poly
			(pts
				(xy -1.82118 -1.277112) (xy -2.539492 -0.558546) (xy -1.462024 -0.19939)
			)
			(stroke
				(width 0)
				(type default)
			)
			(fill yes)
			(layer "F.SilkS")
		)
		(fp_line
			(start 0.8001 -1.050036)
			(end 0.8001 1.050036)
			(stroke
				(width 0.1)
				(type default)
			)
			(layer "F.Fab")
		)
		(fp_line
			(start -0.8001 -1.050036)
			(end 0.8001 -1.050036)
			(stroke
				(width 0.1)
				(type default)
			)
			(layer "F.Fab")
		)
		(fp_line
			(start 0.8001 1.050036)
			(end -0.8001 1.050036)
			(stroke
				(width 0.1)
				(type default)
			)
			(layer "F.Fab")
		)
		(fp_line
			(start -0.8001 1.050036)
			(end -0.8001 -1.050036)
			(stroke
				(width 0.1)
				(type default)
			)
			(layer "F.Fab")
		)
		(fp_poly
			(pts
				(xy -2.458974 -0.508) (xy -2.458974 0.508) (xy -1.442974 0)
			)
			(stroke
				(width 0)
				(type default)
			)
			(fill yes)
			(layer "F.Fab")
		)
		(pad "1_2" smd circle
			(at -0.374904 0 180)
			(size 0 0)
			(layers "F.Cu" "F.Mask" "F.Paste")
			(net "P3V3_AUX")
		)
		(pad "3" smd rect
			(at -0.499872 0.999998 90)
			(size 0.254 0.7112)
			(layers "F.Cu" "F.Mask" "F.Paste")
			(net "GND")
		)
		(pad "4" smd rect
			(at 0 0.999998 90)
			(size 0.254 0.7112)
			(layers "F.Cu" "F.Mask" "F.Paste")
			(net "P3V3_NIC3_CO_ILIMIT")
		)
		(pad "5" smd rect
			(at 0.499872 0.999998 90)
			(size 0.254 0.7112)
			(layers "F.Cu" "F.Mask" "F.Paste")
			(net "P3V3_NIC3_CO_MODE")
		)
		(pad "6_7" smd circle
			(at 0.374904 0)
			(size 0 0)
			(layers "F.Cu" "F.Mask" "F.Paste")
			(net "P3V3_NIC3")
		)
		(pad "8" smd rect
			(at 0.499872 -0.999998 90)
			(size 0.254 0.7112)
			(layers "F.Cu" "F.Mask" "F.Paste")
			(net "P3V3_NIC3_CO_GATE")
		)
		(pad "9" smd rect
			(at 0 -0.999998 90)
			(size 0.254 0.7112)
			(layers "F.Cu" "F.Mask" "F.Paste")
			(net "P3V3_NIC3_CO_EN")
		)
		(pad "10" smd rect
			(at -0.499872 -0.999998 90)
			(size 0.254 0.7112)
			(layers "F.Cu" "F.Mask" "F.Paste")
			(net "P3V3_NIC3_CO_DV_DT")
		)
	)
	(footprint ""
		(layer "F.Cu")
		(at 123.648978 -88.39073)
		(property "Reference" "R1589"
			(at 0 0 0)
			(layer "F.SilkS")
			(hide yes)
			(effects
				(font
					(size 1.27 1.27)
				)
			)
		)
		(property "Value" ""
			(at 0 0 0)
			(layer "F.Fab")
			(effects
				(font
					(size 1.27 1.27)
				)
			)
		)
		(duplicate_pad_numbers_are_jumpers no)
		(fp_line
			(start -0.7874 -0.4064)
			(end 0.7874 -0.4064)
			(stroke
				(width 0.1524)
				(type default)
			)
			(layer "F.SilkS")
		)
		(fp_line
			(start -0.7874 0.4064)
			(end -0.7874 -0.4064)
			(stroke
				(width 0.1524)
				(type default)
			)
			(layer "F.SilkS")
		)
		(fp_line
			(start 0.7874 -0.4064)
			(end 0.7874 0.4064)
			(stroke
				(width 0.1524)
				(type default)
			)
			(layer "F.SilkS")
		)
		(fp_line
			(start 0.7874 0.4064)
			(end -0.7874 0.4064)
			(stroke
				(width 0.1524)
				(type default)
			)
			(layer "F.SilkS")
		)
		(fp_line
			(start -0.67945 -0.305054)
			(end -0.12065 -0.305054)
			(stroke
				(width 0.1)
				(type default)
			)
			(layer "F.Fab")
		)
		(fp_line
			(start -0.67945 0.3048)
			(end -0.67945 -0.305054)
			(stroke
				(width 0.1)
				(type default)
			)
			(layer "F.Fab")
		)
		(fp_line
			(start -0.12065 -0.305054)
			(end -0.12065 -0.2794)
			(stroke
				(width 0.1)
				(type default)
			)
			(layer "F.Fab")
		)
		(fp_line
			(start -0.12065 -0.2794)
			(end 0.12065 -0.2794)
			(stroke
				(width 0.1)
				(type default)
			)
			(layer "F.Fab")
		)
		(fp_line
			(start -0.12065 0.2794)
			(end -0.12065 0.3048)
			(stroke
				(width 0.1)
				(type default)
			)
			(layer "F.Fab")
		)
		(fp_line
			(start -0.12065 0.3048)
			(end -0.67945 0.3048)
			(stroke
				(width 0.1)
				(type default)
			)
			(layer "F.Fab")
		)
		(fp_line
			(start 0.120396 0.2794)
			(end -0.12065 0.2794)
			(stroke
				(width 0.1)
				(type default)
			)
			(layer "F.Fab")
		)
		(fp_line
			(start 0.120396 0.3048)
			(end 0.120396 0.2794)
			(stroke
				(width 0.1)
				(type default)
			)
			(layer "F.Fab")
		)
		(fp_line
			(start 0.12065 -0.3048)
			(end 0.67945 -0.3048)
			(stroke
				(width 0.1)
				(type default)
			)
			(layer "F.Fab")
		)
		(fp_line
			(start 0.12065 -0.2794)
			(end 0.12065 -0.3048)
			(stroke
				(width 0.1)
				(type default)
			)
			(layer "F.Fab")
		)
		(fp_line
			(start 0.67945 -0.3048)
			(end 0.67945 0.3048)
			(stroke
				(width 0.1)
				(type default)
			)
			(layer "F.Fab")
		)
		(fp_line
			(start 0.67945 0.3048)
			(end 0.120396 0.3048)
			(stroke
				(width 0.1)
				(type default)
			)
			(layer "F.Fab")
		)
		(pad "1" smd circle
			(at -0.40005 0)
			(size 0 0)
			(layers "F.Cu" "F.Mask" "F.Paste")
			(net "SMB_BIC_I2C9_MUX0_SSD3_R_SCL")
		)
		(pad "2" smd circle
			(at 0.40005 0)
			(size 0 0)
			(layers "F.Cu" "F.Mask" "F.Paste")
			(net "SMB_BIC_I2C9_MUX0_SSD3_SCL")
		)
	)
	(footprint ""
		(layer "F.Cu")
		(at 444.938658 -22.867366 90)
		(property "Reference" "C3978"
			(at 0 0 90)
			(layer "F.SilkS")
			(hide yes)
			(effects
				(font
					(size 1.27 1.27)
				)
			)
		)
		(property "Value" ""
			(at 0 0 90)
			(layer "F.Fab")
			(effects
				(font
					(size 1.27 1.27)
				)
			)
		)
		(duplicate_pad_numbers_are_jumpers no)
		(fp_line
			(start 0.7874 -0.4064)
			(end 0.7874 0.4064)
			(stroke
				(width 0.1524)
				(type default)
			)
			(layer "F.SilkS")
		)
		(fp_line
			(start -0.7874 -0.4064)
			(end 0.7874 -0.4064)
			(stroke
				(width 0.1524)
				(type default)
			)
			(layer "F.SilkS")
		)
		(fp_line
			(start 0.7874 0.4064)
			(end -0.7874 0.4064)
			(stroke
				(width 0.1524)
				(type default)
			)
			(layer "F.SilkS")
		)
		(fp_line
			(start -0.7874 0.4064)
			(end -0.7874 -0.4064)
			(stroke
				(width 0.1524)
				(type default)
			)
			(layer "F.SilkS")
		)
		(fp_line
			(start -0.12065 -0.305054)
			(end -0.12065 -0.2794)
			(stroke
				(width 0.1)
				(type default)
			)
			(layer "F.Fab")
		)
		(fp_line
			(start -0.67945 -0.305054)
			(end -0.12065 -0.305054)
			(stroke
				(width 0.1)
				(type default)
			)
			(layer "F.Fab")
		)
		(fp_line
			(start 0.67945 -0.3048)
			(end 0.67945 0.3048)
			(stroke
				(width 0.1)
				(type default)
			)
			(layer "F.Fab")
		)
		(fp_line
			(start 0.12065 -0.3048)
			(end 0.67945 -0.3048)
			(stroke
				(width 0.1)
				(type default)
			)
			(layer "F.Fab")
		)
		(fp_line
			(start 0.12065 -0.2794)
			(end 0.12065 -0.3048)
			(stroke
				(width 0.1)
				(type default)
			)
			(layer "F.Fab")
		)
		(fp_line
			(start -0.12065 -0.2794)
			(end 0.12065 -0.2794)
			(stroke
				(width 0.1)
				(type default)
			)
			(layer "F.Fab")
		)
		(fp_line
			(start 0.120396 0.2794)
			(end -0.12065 0.2794)
			(stroke
				(width 0.1)
				(type default)
			)
			(layer "F.Fab")
		)
		(fp_line
			(start -0.12065 0.2794)
			(end -0.12065 0.3048)
			(stroke
				(width 0.1)
				(type default)
			)
			(layer "F.Fab")
		)
		(fp_line
			(start 0.67945 0.3048)
			(end 0.120396 0.3048)
			(stroke
				(width 0.1)
				(type default)
			)
			(layer "F.Fab")
		)
		(fp_line
			(start 0.120396 0.3048)
			(end 0.120396 0.2794)
			(stroke
				(width 0.1)
				(type default)
			)
			(layer "F.Fab")
		)
		(fp_line
			(start -0.12065 0.3048)
			(end -0.67945 0.3048)
			(stroke
				(width 0.1)
				(type default)
			)
			(layer "F.Fab")
		)
		(fp_line
			(start -0.67945 0.3048)
			(end -0.67945 -0.305054)
			(stroke
				(width 0.1)
				(type default)
			)
			(layer "F.Fab")
		)
		(pad "1" smd circle
			(at -0.40005 0 90)
			(size 0 0)
			(layers "F.Cu" "F.Mask" "F.Paste")
			(net "P12V_SSD15")
		)
		(pad "2" smd circle
			(at 0.40005 0 90)
			(size 0 0)
			(layers "F.Cu" "F.Mask" "F.Paste")
			(net "GND")
		)
	)
)
